(kicad_pcb
	(version 20241229)
	(generator "pcbnew")
	(generator_version "9.0")
	(general
		(thickness 1.63)
		(legacy_teardrops no)
	)
	(paper "A4")
	(title_block
		(title "CM4 Baseboard")
		(date "2026-01-05")
		(rev "1.1.1")
		(company "Antmicro Ltd")
		(comment 1 "www.antmicro.com")
		(comment 9 "footprints 236-239 of 506")
	)
	(layers
		(0 "F.Cu" signal)
		(4 "In1.Cu" power)
		(6 "In2.Cu" power)
		(8 "In3.Cu" signal)
		(10 "In4.Cu" signal)
		(2 "B.Cu" signal)
		(9 "F.Adhes" user "F.Adhesive")
		(11 "B.Adhes" user "B.Adhesive")
		(13 "F.Paste" user)
		(15 "B.Paste" user)
		(5 "F.SilkS" user "F.Silkscreen")
		(7 "B.SilkS" user "B.Silkscreen")
		(1 "F.Mask" user)
		(3 "B.Mask" user)
		(17 "Dwgs.User" user "User.Drawings")
		(19 "Cmts.User" user "User.Comments")
		(21 "Eco1.User" user "User.Eco1")
		(23 "Eco2.User" user "User.Eco2")
		(25 "Edge.Cuts" user)
		(27 "Margin" user)
		(31 "F.CrtYd" user "F.Courtyard")
		(29 "B.CrtYd" user "B.Courtyard")
		(35 "F.Fab" user)
		(33 "B.Fab" user)
	)
	(footprint "antmicro-footprints:USB-C_Receptacle_GCT_USB4105-GF-A"
		(layer "F.Cu")
		(at 93.017962 115.6165 180)
		(property "Reference" "J901"
			(at -7.64 3.77 90)
			(layer "F.SilkS")
			(effects
				(font
					(size 0.7 0.7)
					(thickness 0.15)
				)
				(justify right bottom)
			)
		)
		(property "Value" "USB-C_GCT_USB4105-GF-A"
			(at 0 5 0)
			(layer "F.Fab")
			(effects
				(font
					(size 0.7 0.7)
					(thickness 0.15)
				)
				(justify right bottom)
			)
		)
		(property "Datasheet" "https://gct.co/files/drawings/usb4105.pdf"
			(at 0 0 180)
			(layer "F.Fab")
			(hide yes)
			(effects
				(font
					(size 1.27 1.27)
					(thickness 0.15)
				)
			)
		)
		(property "Manufacturer" "GCT"
			(at 0 0 180)
			(unlocked yes)
			(layer "F.Fab")
			(hide yes)
			(effects
				(font
					(size 1 1)
					(thickness 0.15)
				)
			)
		)
		(property "MPN" "USB4105-GF-A"
			(at 0 0 180)
			(unlocked yes)
			(layer "F.Fab")
			(hide yes)
			(effects
				(font
					(size 1 1)
					(thickness 0.15)
				)
			)
		)
		(property "Author" "Antmicro"
			(at 0 0 180)
			(unlocked yes)
			(layer "F.Fab")
			(hide yes)
			(effects
				(font
					(size 1 1)
					(thickness 0.15)
				)
			)
		)
		(property "License" "Apache-2.0"
			(at 0 0 180)
			(unlocked yes)
			(layer "F.Fab")
			(hide yes)
			(effects
				(font
					(size 1 1)
					(thickness 0.15)
				)
			)
		)
		(sheetname "/USB/")
		(sheetfile "usb.kicad_sch")
		(attr smd)
		(fp_line
			(start 4.788 3.854)
			(end 4.788 2.575)
			(stroke
				(width 0.15)
				(type solid)
			)
			(layer "F.SilkS")
		)
		(fp_line
			(start 4.788 -1.395)
			(end 4.788 -0.145)
			(stroke
				(width 0.15)
				(type solid)
			)
			(layer "F.SilkS")
		)
		(fp_line
			(start -4.79 3.854)
			(end 4.788 3.854)
			(stroke
				(width 0.15)
				(type solid)
			)
			(layer "F.SilkS")
		)
		(fp_line
			(start -4.79 2.575)
			(end -4.79 3.854)
			(stroke
				(width 0.15)
				(type solid)
			)
			(layer "F.SilkS")
		)
		(fp_line
			(start -4.79 -1.395)
			(end -4.79 -0.145)
			(stroke
				(width 0.15)
				(type solid)
			)
			(layer "F.SilkS")
		)
		(fp_circle
			(center -3.8 -4.27071)
			(end -3.75 -4.22071)
			(stroke
				(width 0.15)
				(type solid)
			)
			(fill yes)
			(layer "F.SilkS")
		)
		(fp_rect
			(start -5.1 -4.4)
			(end 5.1 3.9)
			(stroke
				(width 0.05)
				(type solid)
			)
			(fill no)
			(layer "F.CrtYd")
		)
		(fp_line
			(start 4.788 3.854)
			(end -4.79 3.854)
			(stroke
				(width 0.15)
				(type solid)
			)
			(layer "F.Fab")
		)
		(fp_line
			(start 4.788 -3.676)
			(end 4.788 3.854)
			(stroke
				(width 0.15)
				(type solid)
			)
			(layer "F.Fab")
		)
		(fp_line
			(start -4.702 3.854)
			(end 4.788 3.854)
			(stroke
				(width 0.15)
				(type solid)
			)
			(layer "F.Fab")
		)
		(fp_line
			(start -4.79 3.854)
			(end -4.79 -3.676)
			(stroke
				(width 0.15)
				(type solid)
			)
			(layer "F.Fab")
		)
		(fp_line
			(start -4.79 -3.676)
			(end 4.788 -3.676)
			(stroke
				(width 0.15)
				(type solid)
			)
			(layer "F.Fab")
		)
		(fp_text user "${REFERENCE}"
			(at -4.79 6.853 180)
			(layer "F.Fab")
			(effects
				(font
					(size 0.7 0.7)
					(thickness 0.15)
				)
				(justify left bottom)
			)
		)
		(fp_text user "PCB-EDGE"
			(at -4.79 5.853 180)
			(layer "F.Fab")
			(effects
				(font
					(size 0.7 0.7)
					(thickness 0.15)
				)
				(justify left bottom)
			)
		)
		(fp_text user "License: Apache-2.0"
			(at -4.79 8.855 180)
			(layer "F.Fab")
			(effects
				(font
					(size 0.7 0.7)
					(thickness 0.15)
				)
				(justify left bottom)
			)
		)
		(fp_text user "Author: Antmicro"
			(at -4.79 7.853 180)
			(layer "F.Fab")
			(effects
				(font
					(size 0.7 0.7)
					(thickness 0.15)
				)
				(justify left bottom)
			)
		)
		(pad "" np_thru_hole circle
			(at -2.891 -2.426 180)
			(size 0.65 0.65)
			(drill 0.65)
			(layers "*.Cu" "*.Mask")
		)
		(pad "" np_thru_hole circle
			(at 2.89 -2.426 180)
			(size 0.65 0.65)
			(drill 0.65)
			(layers "*.Cu" "*.Mask")
		)
		(pad "A1" smd roundrect
			(at -3.202 -3.5 180)
			(size 0.6 1.15)
			(layers "F.Cu" "F.Mask" "F.Paste")
			(roundrect_rratio 0.25)
			(net 3 "GND")
			(pinfunction "GND")
			(pintype "power_in")
		)
		(pad "A4" smd roundrect
			(at -2.4 -3.5 180)
			(size 0.6 1.15)
			(layers "F.Cu" "F.Mask" "F.Paste")
			(roundrect_rratio 0.25)
			(net 24 "/Compute module/USBA_VBUS")
			(pinfunction "VBUS")
			(pintype "power_in")
		)
		(pad "A5" smd roundrect
			(at -1.25 -3.5 180)
			(size 0.3 1.15)
			(layers "F.Cu" "F.Mask" "F.Paste")
			(roundrect_rratio 0.25)
			(net 203 "/USB/USBA_CC1")
			(pinfunction "CC_{1}")
			(pintype "bidirectional")
		)
		(pad "A6" smd roundrect
			(at -0.25 -3.5 180)
			(size 0.3 1.15)
			(layers "F.Cu" "F.Mask" "F.Paste")
			(roundrect_rratio 0.25)
			(net 205 "/USB/AD_P")
			(pinfunction "D_{A}+")
			(pintype "bidirectional")
		)
		(pad "A7" smd roundrect
			(at 0.248 -3.5 180)
			(size 0.3 1.15)
			(layers "F.Cu" "F.Mask" "F.Paste")
			(roundrect_rratio 0.25)
			(net 206 "/USB/AD_N")
			(pinfunction "D_{A}-")
			(pintype "bidirectional")
		)
		(pad "A8" smd roundrect
			(at 1.249 -3.5 180)
			(size 0.3 1.15)
			(layers "F.Cu" "F.Mask" "F.Paste")
			(roundrect_rratio 0.25)
			(net 322 "unconnected-(J901-SBU_{1}-PadA8)")
			(pinfunction "SBU_{1}")
			(pintype "bidirectional+no_connect")
		)
		(pad "A9" smd roundrect
			(at 2.398 -3.5 180)
			(size 0.6 1.15)
			(layers "F.Cu" "F.Mask" "F.Paste")
			(roundrect_rratio 0.25)
			(net 24 "/Compute module/USBA_VBUS")
			(pinfunction "VBUS")
			(pintype "passive")
		)
		(pad "A12" smd roundrect
			(at 3.2 -3.5 180)
			(size 0.6 1.15)
			(layers "F.Cu" "F.Mask" "F.Paste")
			(roundrect_rratio 0.25)
			(net 3 "GND")
			(pinfunction "GND")
			(pintype "passive")
		)
		(pad "B1" smd roundrect
			(at 3.2 -3.5 180)
			(size 0.6 1.15)
			(layers "F.Cu" "F.Mask" "F.Paste")
			(roundrect_rratio 0.25)
			(net 3 "GND")
			(pinfunction "GND")
			(pintype "passive")
		)
		(pad "B4" smd roundrect
			(at 2.398 -3.5 180)
			(size 0.6 1.15)
			(layers "F.Cu" "F.Mask" "F.Paste")
			(roundrect_rratio 0.25)
			(net 24 "/Compute module/USBA_VBUS")
			(pinfunction "VBUS")
			(pintype "passive")
		)
		(pad "B5" smd roundrect
			(at 1.749 -3.5 180)
			(size 0.3 1.15)
			(layers "F.Cu" "F.Mask" "F.Paste")
			(roundrect_rratio 0.25)
			(net 204 "/USB/USBA_CC2")
			(pinfunction "CC_{2}")
			(pintype "bidirectional")
		)
		(pad "B6" smd roundrect
			(at 0.748 -3.5 180)
			(size 0.3 1.15)
			(layers "F.Cu" "F.Mask" "F.Paste")
			(roundrect_rratio 0.25)
			(net 205 "/USB/AD_P")
			(pinfunction "D_{B}+")
			(pintype "bidirectional")
		)
		(pad "B7" smd roundrect
			(at -0.75 -3.5 180)
			(size 0.3 1.15)
			(layers "F.Cu" "F.Mask" "F.Paste")
			(roundrect_rratio 0.25)
			(net 206 "/USB/AD_N")
			(pinfunction "D_{B}-")
			(pintype "bidirectional")
		)
		(pad "B8" smd roundrect
			(at -1.75 -3.5 180)
			(size 0.3 1.15)
			(layers "F.Cu" "F.Mask" "F.Paste")
			(roundrect_rratio 0.25)
			(net 321 "unconnected-(J901-SBU_{2}-PadB8)")
			(pinfunction "SBU_{2}")
			(pintype "bidirectional+no_connect")
		)
		(pad "B9" smd roundrect
			(at -2.4 -3.5 180)
			(size 0.6 1.15)
			(layers "F.Cu" "F.Mask" "F.Paste")
			(roundrect_rratio 0.25)
			(net 24 "/Compute module/USBA_VBUS")
			(pinfunction "VBUS")
			(pintype "passive")
		)
		(pad "B12" smd roundrect
			(at -3.202 -3.5 180)
			(size 0.6 1.15)
			(layers "F.Cu" "F.Mask" "F.Paste")
			(roundrect_rratio 0.25)
			(net 3 "GND")
			(pinfunction "GND")
			(pintype "passive")
		)
		(pad "SH" thru_hole oval
			(at -4.321 -2.926 180)
			(size 1.05 2.1)
			(drill oval 0.6 1.7)
			(layers "*.Cu" "*.Mask")
			(remove_unused_layers no)
			(net 3 "GND")
			(pinfunction "SH")
			(pintype "passive")
		)
		(pad "SH" thru_hole oval
			(at -4.321 1.255 180)
			(size 1 2)
			(drill oval 0.6 1.4)
			(layers "*.Cu" "*.Mask")
			(remove_unused_layers no)
			(net 3 "GND")
			(pinfunction "SH")
			(pintype "passive")
		)
		(pad "SH" thru_hole oval
			(at 4.32 -2.926 180)
			(size 1.05 2.1)
			(drill oval 0.6 1.7)
			(layers "*.Cu" "*.Mask")
			(remove_unused_layers no)
			(net 3 "GND")
			(pinfunction "SH")
			(pintype "passive")
		)
		(pad "SH" thru_hole oval
			(at 4.32 1.255 180)
			(size 1 2)
			(drill oval 0.6 1.4)
			(layers "*.Cu" "*.Mask")
			(remove_unused_layers no)
			(net 3 "GND")
			(pinfunction "SH")
			(pintype "passive")
		)
	)
	(footprint "antmicro-footprints:C_0402_1005Metric"
		(layer "F.Cu")
		(at 71.317962 167.0565 -90)
		(descr "Capacitor SMD 0402")
		(tags "capacitor SMD 0402")
		(property "Reference" "C802"
			(at -1.7065 0.517962 90)
			(layer "F.SilkS")
			(effects
				(font
					(size 0.7 0.7)
					(thickness 0.15)
				)
				(justify right bottom)
			)
		)
		(property "Value" "C_1u_0402"
			(at -1.022927 2.155213 90)
			(layer "F.Fab")
			(effects
				(font
					(size 0.7 0.7)
					(thickness 0.15)
				)
				(justify right bottom)
			)
		)
		(property "Datasheet" "https://product.tdk.com/en/search/capacitor/ceramic/mlcc/info?part_no=C1005X6S1A105K050BC"
			(at 0 0 270)
			(layer "F.Fab")
			(hide yes)
			(effects
				(font
					(size 1.27 1.27)
					(thickness 0.15)
				)
			)
		)
		(property "MPN" "C1005X6S1A105K050BC"
			(at 0 0 270)
			(unlocked yes)
			(layer "F.Fab")
			(hide yes)
			(effects
				(font
					(size 1 1)
					(thickness 0.15)
				)
			)
		)
		(property "Manufacturer" "TDK"
			(at 0 0 270)
			(unlocked yes)
			(layer "F.Fab")
			(hide yes)
			(effects
				(font
					(size 1 1)
					(thickness 0.15)
				)
			)
		)
		(property "License" "Apache-2.0"
			(at 0 0 270)
			(unlocked yes)
			(layer "F.Fab")
			(hide yes)
			(effects
				(font
					(size 1 1)
					(thickness 0.15)
				)
			)
		)
		(property "Author" "Antmicro"
			(at 0 0 270)
			(unlocked yes)
			(layer "F.Fab")
			(hide yes)
			(effects
				(font
					(size 1 1)
					(thickness 0.15)
				)
			)
		)
		(property "Val" "1u"
			(at 0 0 270)
			(unlocked yes)
			(layer "F.Fab")
			(hide yes)
			(effects
				(font
					(size 1 1)
					(thickness 0.15)
				)
			)
		)
		(property "Voltage" ""
			(at 0 0 270)
			(unlocked yes)
			(layer "F.Fab")
			(hide yes)
			(effects
				(font
					(size 1 1)
					(thickness 0.15)
				)
			)
		)
		(property "Dielectric" ""
			(at 0 0 270)
			(unlocked yes)
			(layer "F.Fab")
			(hide yes)
			(effects
				(font
					(size 1 1)
					(thickness 0.15)
				)
			)
		)
		(sheetname "/Peripherals/")
		(sheetfile "peripherals.kicad_sch")
		(attr smd)
		(fp_rect
			(start -0.925 -0.47)
			(end 0.925 0.47)
			(stroke
				(width 0.05)
				(type default)
			)
			(fill no)
			(layer "F.CrtYd")
		)
		(fp_line
			(start -0.494 0.248)
			(end -0.494 -0.25)
			(stroke
				(width 0.15)
				(type solid)
			)
			(layer "F.Fab")
		)
		(fp_line
			(start 0.504 0.248)
			(end -0.494 0.248)
			(stroke
				(width 0.15)
				(type solid)
			)
			(layer "F.Fab")
		)
		(fp_line
			(start -0.494 -0.25)
			(end 0.504 -0.25)
			(stroke
				(width 0.15)
				(type solid)
			)
			(layer "F.Fab")
		)
		(fp_line
			(start 0.504 -0.25)
			(end 0.504 0.248)
			(stroke
				(width 0.15)
				(type solid)
			)
			(layer "F.Fab")
		)
		(fp_text user "Author: Antmicro"
			(at -0.939 3.399 270)
			(layer "F.Fab")
			(effects
				(font
					(size 0.7 0.7)
					(thickness 0.15)
				)
				(justify left bottom)
			)
		)
		(fp_text user "${REFERENCE}"
			(at -0.939 4.599 270)
			(layer "F.Fab")
			(effects
				(font
					(size 0.7 0.7)
					(thickness 0.15)
				)
				(justify left bottom)
			)
		)
		(fp_text user "License: Apache-2.0"
			(at -0.939 5.799 270)
			(layer "F.Fab")
			(effects
				(font
					(size 0.7 0.7)
					(thickness 0.15)
				)
				(justify left bottom)
			)
		)
		(pad "1" smd roundrect
			(at -0.48 0 270)
			(size 0.59 0.64)
			(layers "F.Cu" "F.Mask" "F.Paste")
			(roundrect_rratio 0.25)
			(net 3 "GND")
			(pintype "passive")
		)
		(pad "2" smd roundrect
			(at 0.48 0 270)
			(size 0.59 0.64)
			(layers "F.Cu" "F.Mask" "F.Paste")
			(roundrect_rratio 0.25)
			(net 9 "+3V3")
			(pintype "passive")
		)
	)
	(footprint "antmicro-footprints:R_0402_1005Metric"
		(layer "F.Cu")
		(at 58.992962 177.3255 180)
		(descr "Resistor SMD 0402")
		(tags "resistor SMD 0402")
		(property "Reference" "R809"
			(at -1.507038 -0.4245 0)
			(layer "F.SilkS")
			(effects
				(font
					(size 0.7 0.7)
					(thickness 0.15)
				)
				(justify right top)
			)
		)
		(property "Value" "R_0R_0402"
			(at -1.011843 1.772046 0)
			(layer "F.Fab")
			(effects
				(font
					(size 0.7 0.7)
					(thickness 0.15)
				)
				(justify right top)
			)
		)
		(property "Datasheet" "https://industrial.panasonic.com/cdbs/www-data/pdf/RDA0000/AOA0000C301.pdf"
			(at 0 0 0)
			(layer "F.Fab")
			(hide yes)
			(effects
				(font
					(size 1.27 1.27)
					(thickness 0.15)
				)
			)
		)
		(property "Description" "SMD Chip Resistor, Jumper, 0 ohm, 100 mW, 0402 [1005 Metric], Thick Film, General Purpose"
			(at 0 0 0)
			(layer "F.Fab")
			(hide yes)
			(effects
				(font
					(size 1.27 1.27)
					(thickness 0.15)
				)
			)
		)
		(property "MPN" "ERJ2GE0R00X"
			(at 0 0 180)
			(unlocked yes)
			(layer "F.Fab")
			(hide yes)
			(effects
				(font
					(size 1 1)
					(thickness 0.15)
				)
			)
		)
		(property "Manufacturer" "Panasonic"
			(at 0 0 180)
			(unlocked yes)
			(layer "F.Fab")
			(hide yes)
			(effects
				(font
					(size 1 1)
					(thickness 0.15)
				)
			)
		)
		(property "License" "Apache-2.0"
			(at 0 0 180)
			(unlocked yes)
			(layer "F.Fab")
			(hide yes)
			(effects
				(font
					(size 1 1)
					(thickness 0.15)
				)
			)
		)
		(property "Author" "Antmicro"
			(at 0 0 180)
			(unlocked yes)
			(layer "F.Fab")
			(hide yes)
			(effects
				(font
					(size 1 1)
					(thickness 0.15)
				)
			)
		)
		(property "Val" "0R"
			(at 0 0 180)
			(unlocked yes)
			(layer "F.Fab")
			(hide yes)
			(effects
				(font
					(size 1 1)
					(thickness 0.15)
				)
			)
		)
		(property "Tolerance" "~"
			(at 0 0 180)
			(unlocked yes)
			(layer "F.Fab")
			(hide yes)
			(effects
				(font
					(size 1 1)
					(thickness 0.15)
				)
			)
		)
		(property "Current" "1A"
			(at 0 0 180)
			(unlocked yes)
			(layer "F.Fab")
			(hide yes)
			(effects
				(font
					(size 1 1)
					(thickness 0.15)
				)
			)
		)
		(sheetname "/Peripherals/")
		(sheetfile "peripherals.kicad_sch")
		(attr smd)
		(fp_poly
			(pts
				(xy -0.925 -0.47) (xy 0.925 -0.47) (xy 0.925 0.47) (xy -0.925 0.47)
			)
			(stroke
				(width 0.05)
				(type default)
			)
			(fill no)
			(layer "F.CrtYd")
		)
		(fp_poly
			(pts
				(xy -0.5 -0.25) (xy 0.5 -0.25) (xy 0.5 0.25) (xy -0.5 0.25)
			)
			(stroke
				(width 0.15)
				(type solid)
			)
			(fill no)
			(layer "F.Fab")
		)
		(fp_text user "License: Apache-2.0"
			(at -0.949999 5.169 0)
			(layer "F.Fab")
			(effects
				(font
					(size 0.7 0.7)
					(thickness 0.15)
				)
				(justify right top)
			)
		)
		(fp_text user "${REFERENCE}"
			(at -0.95 3.168 0)
			(layer "F.Fab")
			(effects
				(font
					(size 0.7 0.7)
					(thickness 0.15)
				)
				(justify right top)
			)
		)
		(fp_text user "Author: Antmicro"
			(at -0.95 4.169 0)
			(layer "F.Fab")
			(effects
				(font
					(size 0.7 0.7)
					(thickness 0.15)
				)
				(justify right top)
			)
		)
		(pad "1" smd roundrect
			(at -0.48 0 180)
			(size 0.59 0.64)
			(layers "F.Cu" "F.Mask" "F.Paste")
			(roundrect_rratio 0.25)
			(net 100 "Net-(C811-Pad2)")
			(pintype "passive")
		)
		(pad "2" smd roundrect
			(at 0.48 0 180)
			(size 0.59 0.64)
			(layers "F.Cu" "F.Mask" "F.Paste")
			(roundrect_rratio 0.25)
			(net 320 "Net-(J804-Pad2)")
			(pintype "passive")
		)
	)
	(footprint "antmicro-footprints:R_0402_1005Metric"
		(layer "F.Cu")
		(at 120.3 155.5915 180)
		(descr "Resistor SMD 0402")
		(tags "resistor SMD 0402")
		(property "Reference" "R219"
			(at -4.3 -0.175 180)
			(layer "F.SilkS")
			(effects
				(font
					(size 0.7 0.7)
					(thickness 0.15)
				)
				(justify left bottom)
			)
		)
		(property "Value" "R_0R_0402"
			(at -1.011843 1.772047 180)
			(layer "F.Fab")
			(effects
				(font
					(size 0.7 0.7)
					(thickness 0.15)
				)
				(justify left bottom)
			)
		)
		(property "Datasheet" "https://industrial.panasonic.com/cdbs/www-data/pdf/RDA0000/AOA0000C301.pdf"
			(at 0 0 180)
			(layer "F.Fab")
			(hide yes)
			(effects
				(font
					(size 1.27 1.27)
					(thickness 0.15)
				)
			)
		)
		(property "Manufacturer" "Panasonic"
			(at 0 0 180)
			(unlocked yes)
			(layer "F.Fab")
			(hide yes)
			(effects
				(font
					(size 1 1)
					(thickness 0.15)
				)
			)
		)
		(property "MPN" "ERJ2GE0R00X"
			(at 0 0 180)
			(unlocked yes)
			(layer "F.Fab")
			(hide yes)
			(effects
				(font
					(size 1 1)
					(thickness 0.15)
				)
			)
		)
		(property "Val" "0R"
			(at 0 0 180)
			(unlocked yes)
			(layer "F.Fab")
			(hide yes)
			(effects
				(font
					(size 1 1)
					(thickness 0.15)
				)
			)
		)
		(property "License" "Apache-2.0"
			(at 0 0 180)
			(unlocked yes)
			(layer "F.Fab")
			(hide yes)
			(effects
				(font
					(size 1 1)
					(thickness 0.15)
				)
			)
		)
		(property "Author" "Antmicro"
			(at 0 0 180)
			(unlocked yes)
			(layer "F.Fab")
			(hide yes)
			(effects
				(font
					(size 1 1)
					(thickness 0.15)
				)
			)
		)
		(property "Tolerance" "~"
			(at 0 0 180)
			(unlocked yes)
			(layer "F.Fab")
			(hide yes)
			(effects
				(font
					(size 1 1)
					(thickness 0.15)
				)
			)
		)
		(property "Current" "1A"
			(at 0 0 180)
			(unlocked yes)
			(layer "F.Fab")
			(hide yes)
			(effects
				(font
					(size 1 1)
					(thickness 0.15)
				)
			)
		)
		(sheetname "/Compute module/")
		(sheetfile "compute-module.kicad_sch")
		(attr smd)
		(fp_rect
			(start -0.925 -0.47)
			(end 0.925 0.47)
			(stroke
				(width 0.05)
				(type default)
			)
			(fill no)
			(layer "F.CrtYd")
		)
		(fp_rect
			(start -0.5 -0.25)
			(end 0.5 0.25)
			(stroke
				(width 0.15)
				(type solid)
			)
			(fill no)
			(layer "F.Fab")
		)
		(fp_text user "${REFERENCE}"
			(at -0.95 3.168 180)
			(layer "F.Fab")
			(effects
				(font
					(size 0.7 0.7)
					(thickness 0.15)
				)
				(justify left bottom)
			)
		)
		(fp_text user "Author: Antmicro"
			(at -0.95 4.169 180)
			(layer "F.Fab")
			(effects
				(font
					(size 0.7 0.7)
					(thickness 0.15)
				)
				(justify left bottom)
			)
		)
		(fp_text user "License: Apache-2.0"
			(at -0.95 5.169 180)
			(layer "F.Fab")
			(effects
				(font
					(size 0.7 0.7)
					(thickness 0.15)
				)
				(justify left bottom)
			)
		)
		(pad "1" smd roundrect
			(at -0.48 0 180)
			(size 0.59 0.64)
			(layers "F.Cu" "F.Mask" "F.Paste")
			(roundrect_rratio 0.25)
			(net 166 "/Compute module/NVMe.RX1_N")
			(pintype "passive")
		)
		(pad "2" smd roundrect
			(at 0.48 0 180)
			(size 0.59 0.64)
			(layers "F.Cu" "F.Mask" "F.Paste")
			(roundrect_rratio 0.25)
			(net 148 "/Compute module/R1_N")
			(pintype "passive")
		)
	)
)
